(kicad_pcb
	(version 20260206)
	(generator "pcbnew")
	(generator_version "10.0")
	(general
		(thickness 1.6)
		(legacy_teardrops no)
	)
	(paper "A4")
	(title_block
		(title "panther-plus-userver — 13130-1b_20150205.brd")
		(comment 1 "Honey Badger (Wiwynn) / footprint 1214 of 1509 (DIMM3), pads 44-50 of 210")
	)
	(layers
		(0 "F.Cu" signal "TOP")
		(4 "In1.Cu" signal "L2")
		(6 "In2.Cu" signal "L3")
		(8 "In3.Cu" signal "L4")
		(10 "In4.Cu" signal "L5")
		(12 "In5.Cu" signal "L6")
		(14 "In6.Cu" signal "L7")
		(16 "In7.Cu" signal "L8")
		(18 "In8.Cu" signal "L9")
		(20 "In9.Cu" signal "L10")
		(22 "In10.Cu" signal "L11")
		(2 "B.Cu" signal "BOTTOM")
		(9 "F.Adhes" user "F.Adhesive")
		(11 "B.Adhes" user "B.Adhesive")
		(13 "F.Paste" user "Package Geometry/Pastemask Top")
		(15 "B.Paste" user "Package Geometry/Pastemask Bottom")
		(5 "F.SilkS" user "Ref Des/Silkscreen Top")
		(7 "B.SilkS" user "Ref Des/Silkscreen Bottom")
		(1 "F.Mask" user "Board Geometry/Soldermask Top")
		(3 "B.Mask" user "Board Geometry/Soldermask Bottom")
		(17 "Dwgs.User" user "User.Drawings")
		(19 "Cmts.User" user "User.Comments")
		(21 "Eco1.User" user "User.Eco1")
		(23 "Eco2.User" user "User.Eco2")
		(25 "Edge.Cuts" user "Board Geometry/Outline")
		(27 "Margin" user)
		(31 "F.CrtYd" user "Package Geometry/Place Bound Top")
		(29 "B.CrtYd" user "Package Geometry/Place Bound Bottom")
		(35 "F.Fab" user "Ref Des/Assembly Top")
		(33 "B.Fab" user "Ref Des/Assembly Bottom")
	)
	(footprint ""
		(layer "B.Cu")
		(at 159.999934 -5.790692)
		(property "Reference" "DIMM3"
			(at 0 0 0)
			(layer "B.SilkS")
			(hide yes)
			(effects
				(font
					(size 1.27 1.27)
				)
				(justify mirror)
			)
		)
		(property "Value" "DDR3-204P-142-COLAY-1-GP-U"
			(at 41.312338 -16.676878 0)
			(unlocked yes)
			(layer "B.Fab")
			(hide yes)
			(effects
				(font
					(size 1.016 1.016)
					(thickness 0.1524)
				)
				(justify mirror)
			)
		)
		(property "Device Type" "AS0A626-J8R6-7H-COLAY-1"
			(at 41.312338 -18.200878 0)
			(unlocked yes)
			(layer "B.Fab")
			(hide yes)
			(effects
				(font
					(size 1.016 1.016)
					(thickness 0.1524)
				)
				(justify mirror)
			)
		)
		(duplicate_pad_numbers_are_jumpers no)
		(pad "42" smd custom
			(at -19.349974 4.100068 180)
			(size 0.1143 0.1143)
			(layers "B.Cu" "B.Mask" "B.Paste")
			(net "M_B_DQ21")
			(options
				(clearance outline)
				(anchor circle)
			)
			(primitives
				(gr_poly
					(pts
						(xy 0 -0.9017) (xy -0.03175 -0.89916) (xy -0.0635 -0.889) (xy -0.09144 -0.87376) (xy -0.11684 -0.85344)
						(xy -0.13716 -0.82804) (xy -0.1524 -0.8001) (xy -0.16256 -0.76835) (xy -0.1651 -0.7366) (xy -0.1651 0.13462)
						(xy -0.17272 0.14224) (xy -0.19812 0.1778) (xy -0.2032 0.18796) (xy -0.20701 0.19685) (xy -0.21209 0.20701)
						(xy -0.2159 0.21717) (xy -0.21844 0.22733) (xy -0.22225 0.23876) (xy -0.22352 0.24892) (xy -0.22606 0.25908)
						(xy -0.22733 0.27051) (xy -0.22733 0.28067) (xy -0.2286 0.2921) (xy -0.22733 0.30353) (xy -0.22733 0.31369)
						(xy -0.22606 0.32512) (xy -0.22352 0.33528) (xy -0.22225 0.34544) (xy -0.21844 0.35687) (xy -0.2159 0.36703)
						(xy -0.21209 0.37719) (xy -0.20701 0.38735) (xy -0.2032 0.39624) (xy -0.19812 0.4064) (xy -0.17272 0.44196)
						(xy -0.1651 0.44958) (xy -0.1651 0.7366) (xy -0.16256 0.76835) (xy -0.1524 0.8001) (xy -0.13716 0.82804)
						(xy -0.11684 0.85344) (xy -0.09144 0.87376) (xy -0.0635 0.889) (xy -0.03175 0.89916) (xy 0 0.9017)
						(xy 0.03175 0.89916) (xy 0.0635 0.889) (xy 0.09144 0.87376) (xy 0.11684 0.85344) (xy 0.13716 0.82804)
						(xy 0.1524 0.8001) (xy 0.16256 0.76835) (xy 0.1651 0.7366) (xy 0.1651 0.44958) (xy 0.17272 0.44196)
						(xy 0.19812 0.4064) (xy 0.2032 0.39624) (xy 0.20701 0.38735) (xy 0.21209 0.37719) (xy 0.2159 0.36703)
						(xy 0.21844 0.35687) (xy 0.22225 0.34544) (xy 0.22352 0.33528) (xy 0.22606 0.32512) (xy 0.22733 0.31369)
						(xy 0.22733 0.30353) (xy 0.2286 0.2921) (xy 0.22733 0.28067) (xy 0.22733 0.27051) (xy 0.22606 0.25908)
						(xy 0.22352 0.24892) (xy 0.22225 0.23876) (xy 0.21844 0.22733) (xy 0.2159 0.21717) (xy 0.21209 0.20701)
						(xy 0.20701 0.19685) (xy 0.2032 0.18796) (xy 0.19812 0.1778) (xy 0.17272 0.14224) (xy 0.1651 0.13462)
						(xy 0.1651 -0.7366) (xy 0.16256 -0.76835) (xy 0.1524 -0.8001) (xy 0.13716 -0.82804) (xy 0.11684 -0.85344)
						(xy 0.09144 -0.87376) (xy 0.0635 -0.889) (xy 0.03175 -0.89916)
					)
					(width 0)
					(fill yes)
				)
			)
		)
		(pad "43" smd custom
			(at -19.05 -4.100068 180)
			(size 0.1143 0.1143)
			(layers "B.Cu" "B.Mask" "B.Paste")
			(net "M_B_DQS_DN2")
			(options
				(clearance outline)
				(anchor circle)
			)
			(primitives
				(gr_poly
					(pts
						(xy 0 -0.9017) (xy -0.03175 -0.89916) (xy -0.0635 -0.889) (xy -0.09144 -0.87376) (xy -0.11684 -0.85344)
						(xy -0.13716 -0.82804) (xy -0.1524 -0.8001) (xy -0.16256 -0.76835) (xy -0.1651 -0.7366) (xy -0.1651 -0.19685)
						(xy -0.17272 -0.18923) (xy -0.17907 -0.18034) (xy -0.18669 -0.17145) (xy -0.19177 -0.16256) (xy -0.19812 -0.15367)
						(xy -0.20828 -0.13335) (xy -0.21971 -0.10287) (xy -0.22225 -0.09271) (xy -0.22479 -0.08128) (xy -0.22606 -0.07112)
						(xy -0.2286 -0.05969) (xy -0.2286 -0.01651) (xy -0.22606 -0.00508) (xy -0.22479 0.00508) (xy -0.22225 0.01651)
						(xy -0.21971 0.02667) (xy -0.20828 0.05715) (xy -0.19812 0.07747) (xy -0.19177 0.08636) (xy -0.18669 0.09525)
						(xy -0.17907 0.10414) (xy -0.17272 0.11303) (xy -0.1651 0.12065) (xy -0.1651 0.7366) (xy -0.16256 0.76835)
						(xy -0.1524 0.8001) (xy -0.13716 0.82804) (xy -0.11684 0.85344) (xy -0.09144 0.87376) (xy -0.0635 0.889)
						(xy -0.03175 0.89916) (xy 0 0.9017) (xy 0.03175 0.89916) (xy 0.0635 0.889) (xy 0.09144 0.87376)
						(xy 0.11684 0.85344) (xy 0.13716 0.82804) (xy 0.1524 0.8001) (xy 0.16256 0.76835) (xy 0.1651 0.7366)
						(xy 0.1651 0.11938) (xy 0.17272 0.11176) (xy 0.19812 0.0762) (xy 0.2032 0.06604) (xy 0.20701 0.05715)
						(xy 0.21209 0.04699) (xy 0.2159 0.03683) (xy 0.21844 0.02667) (xy 0.22225 0.01524) (xy 0.22352 0.00508)
						(xy 0.22606 -0.00508) (xy 0.22733 -0.01651) (xy 0.22733 -0.02667) (xy 0.2286 -0.0381) (xy 0.22733 -0.04953)
						(xy 0.22733 -0.05969) (xy 0.22606 -0.07112) (xy 0.22352 -0.08128) (xy 0.22225 -0.09144) (xy 0.21844 -0.10287)
						(xy 0.2159 -0.11303) (xy 0.21209 -0.12319) (xy 0.20701 -0.13335) (xy 0.2032 -0.14224) (xy 0.19812 -0.1524)
						(xy 0.17272 -0.18796) (xy 0.1651 -0.19558) (xy 0.1651 -0.7366) (xy 0.16256 -0.76835) (xy 0.1524 -0.8001)
						(xy 0.13716 -0.82804) (xy 0.11684 -0.85344) (xy 0.09144 -0.87376) (xy 0.0635 -0.889) (xy 0.03175 -0.89916)
					)
					(width 0)
					(fill yes)
				)
			)
		)
		(pad "44" smd custom
			(at -18.750026 4.100068 180)
			(size 0.1143 0.1143)
			(layers "B.Cu" "B.Mask" "B.Paste")
			(net "GND")
			(options
				(clearance outline)
				(anchor circle)
			)
			(primitives
				(gr_poly
					(pts
						(xy 0 -0.9017) (xy -0.03175 -0.89916) (xy -0.0635 -0.889) (xy -0.09144 -0.87376) (xy -0.11684 -0.85344)
						(xy -0.13716 -0.82804) (xy -0.1524 -0.8001) (xy -0.16256 -0.76835) (xy -0.1651 -0.7366) (xy -0.1651 -0.11938)
						(xy -0.17272 -0.11176) (xy -0.19812 -0.0762) (xy -0.2032 -0.06604) (xy -0.20701 -0.05715) (xy -0.21209 -0.04699)
						(xy -0.2159 -0.03683) (xy -0.21844 -0.02667) (xy -0.22225 -0.01524) (xy -0.22352 -0.00508) (xy -0.22606 0.00508)
						(xy -0.22733 0.01651) (xy -0.22733 0.02667) (xy -0.2286 0.0381) (xy -0.22733 0.04953) (xy -0.22733 0.05969)
						(xy -0.22606 0.07112) (xy -0.22352 0.08128) (xy -0.22225 0.09144) (xy -0.21844 0.10287) (xy -0.2159 0.11303)
						(xy -0.21209 0.12319) (xy -0.20701 0.13335) (xy -0.2032 0.14224) (xy -0.19812 0.1524) (xy -0.17272 0.18796)
						(xy -0.1651 0.19558) (xy -0.1651 0.7366) (xy -0.16256 0.76835) (xy -0.1524 0.8001) (xy -0.13716 0.82804)
						(xy -0.11684 0.85344) (xy -0.09144 0.87376) (xy -0.0635 0.889) (xy -0.03175 0.89916) (xy 0 0.9017)
						(xy 0.03175 0.89916) (xy 0.0635 0.889) (xy 0.09144 0.87376) (xy 0.11684 0.85344) (xy 0.13716 0.82804)
						(xy 0.1524 0.8001) (xy 0.16256 0.76835) (xy 0.1651 0.7366) (xy 0.1651 0.19685) (xy 0.17272 0.18923)
						(xy 0.17907 0.18034) (xy 0.18669 0.17145) (xy 0.19177 0.16256) (xy 0.19812 0.15367) (xy 0.20828 0.13335)
						(xy 0.21971 0.10287) (xy 0.22225 0.09271) (xy 0.22479 0.08128) (xy 0.22606 0.07112) (xy 0.2286 0.05969)
						(xy 0.2286 0.01651) (xy 0.22606 0.00508) (xy 0.22479 -0.00508) (xy 0.22225 -0.01651) (xy 0.21971 -0.02667)
						(xy 0.20828 -0.05715) (xy 0.19812 -0.07747) (xy 0.19177 -0.08636) (xy 0.18669 -0.09525) (xy 0.17907 -0.10414)
						(xy 0.17272 -0.11303) (xy 0.1651 -0.12065) (xy 0.1651 -0.7366) (xy 0.16256 -0.76835) (xy 0.1524 -0.8001)
						(xy 0.13716 -0.82804) (xy 0.11684 -0.85344) (xy 0.09144 -0.87376) (xy 0.0635 -0.889) (xy 0.03175 -0.89916)
					)
					(width 0)
					(fill yes)
				)
			)
		)
		(pad "45" smd custom
			(at -18.450052 -4.100068 180)
			(size 0.1143 0.1143)
			(layers "B.Cu" "B.Mask" "B.Paste")
			(net "M_B_DQS_DP2")
			(options
				(clearance outline)
				(anchor circle)
			)
			(primitives
				(gr_poly
					(pts
						(xy 0 -0.9017) (xy -0.03175 -0.89916) (xy -0.0635 -0.889) (xy -0.09144 -0.87376) (xy -0.11684 -0.85344)
						(xy -0.13716 -0.82804) (xy -0.1524 -0.8001) (xy -0.16256 -0.76835) (xy -0.1651 -0.7366) (xy -0.1651 -0.44958)
						(xy -0.17272 -0.44196) (xy -0.19812 -0.4064) (xy -0.2032 -0.39624) (xy -0.20701 -0.38735) (xy -0.21209 -0.37719)
						(xy -0.2159 -0.36703) (xy -0.21844 -0.35687) (xy -0.22225 -0.34544) (xy -0.22352 -0.33528) (xy -0.22606 -0.32512)
						(xy -0.22733 -0.31369) (xy -0.22733 -0.30353) (xy -0.2286 -0.2921) (xy -0.22733 -0.28067) (xy -0.22733 -0.27051)
						(xy -0.22606 -0.25908) (xy -0.22352 -0.24892) (xy -0.22225 -0.23876) (xy -0.21844 -0.22733) (xy -0.2159 -0.21717)
						(xy -0.21209 -0.20701) (xy -0.20701 -0.19685) (xy -0.2032 -0.18796) (xy -0.19812 -0.1778) (xy -0.17272 -0.14224)
						(xy -0.1651 -0.13462) (xy -0.1651 0.7366) (xy -0.16256 0.76835) (xy -0.1524 0.8001) (xy -0.13716 0.82804)
						(xy -0.11684 0.85344) (xy -0.09144 0.87376) (xy -0.0635 0.889) (xy -0.03175 0.89916) (xy 0 0.9017)
						(xy 0.03175 0.89916) (xy 0.0635 0.889) (xy 0.09144 0.87376) (xy 0.11684 0.85344) (xy 0.13716 0.82804)
						(xy 0.1524 0.8001) (xy 0.16256 0.76835) (xy 0.1651 0.7366) (xy 0.1651 -0.13462) (xy 0.17272 -0.14224)
						(xy 0.19812 -0.1778) (xy 0.2032 -0.18796) (xy 0.20701 -0.19685) (xy 0.21209 -0.20701) (xy 0.2159 -0.21717)
						(xy 0.21844 -0.22733) (xy 0.22225 -0.23876) (xy 0.22352 -0.24892) (xy 0.22606 -0.25908) (xy 0.22733 -0.27051)
						(xy 0.22733 -0.28067) (xy 0.2286 -0.2921) (xy 0.22733 -0.30353) (xy 0.22733 -0.31369) (xy 0.22606 -0.32512)
						(xy 0.22352 -0.33528) (xy 0.22225 -0.34544) (xy 0.21844 -0.35687) (xy 0.2159 -0.36703) (xy 0.21209 -0.37719)
						(xy 0.20701 -0.38735) (xy 0.2032 -0.39624) (xy 0.19812 -0.4064) (xy 0.17272 -0.44196) (xy 0.1651 -0.44958)
						(xy 0.1651 -0.7366) (xy 0.16256 -0.76835) (xy 0.1524 -0.8001) (xy 0.13716 -0.82804) (xy 0.11684 -0.85344)
						(xy 0.09144 -0.87376) (xy 0.0635 -0.889) (xy 0.03175 -0.89916)
					)
					(width 0)
					(fill yes)
				)
			)
		)
		(pad "46" smd custom
			(at -18.150078 4.100068 180)
			(size 0.1143 0.1143)
			(layers "B.Cu" "B.Mask" "B.Paste")
			(net "GND")
			(options
				(clearance outline)
				(anchor circle)
			)
			(primitives
				(gr_poly
					(pts
						(xy 0 -0.9017) (xy -0.03175 -0.89916) (xy -0.0635 -0.889) (xy -0.09144 -0.87376) (xy -0.11684 -0.85344)
						(xy -0.13716 -0.82804) (xy -0.1524 -0.8001) (xy -0.16256 -0.76835) (xy -0.1651 -0.7366) (xy -0.1651 0.13462)
						(xy -0.17272 0.14224) (xy -0.19812 0.1778) (xy -0.2032 0.18796) (xy -0.20701 0.19685) (xy -0.21209 0.20701)
						(xy -0.2159 0.21717) (xy -0.21844 0.22733) (xy -0.22225 0.23876) (xy -0.22352 0.24892) (xy -0.22606 0.25908)
						(xy -0.22733 0.27051) (xy -0.22733 0.28067) (xy -0.2286 0.2921) (xy -0.22733 0.30353) (xy -0.22733 0.31369)
						(xy -0.22606 0.32512) (xy -0.22352 0.33528) (xy -0.22225 0.34544) (xy -0.21844 0.35687) (xy -0.2159 0.36703)
						(xy -0.21209 0.37719) (xy -0.20701 0.38735) (xy -0.2032 0.39624) (xy -0.19812 0.4064) (xy -0.17272 0.44196)
						(xy -0.1651 0.44958) (xy -0.1651 0.7366) (xy -0.16256 0.76835) (xy -0.1524 0.8001) (xy -0.13716 0.82804)
						(xy -0.11684 0.85344) (xy -0.09144 0.87376) (xy -0.0635 0.889) (xy -0.03175 0.89916) (xy 0 0.9017)
						(xy 0.03175 0.89916) (xy 0.0635 0.889) (xy 0.09144 0.87376) (xy 0.11684 0.85344) (xy 0.13716 0.82804)
						(xy 0.1524 0.8001) (xy 0.16256 0.76835) (xy 0.1651 0.7366) (xy 0.1651 0.44958) (xy 0.17272 0.44196)
						(xy 0.19812 0.4064) (xy 0.2032 0.39624) (xy 0.20701 0.38735) (xy 0.21209 0.37719) (xy 0.2159 0.36703)
						(xy 0.21844 0.35687) (xy 0.22225 0.34544) (xy 0.22352 0.33528) (xy 0.22606 0.32512) (xy 0.22733 0.31369)
						(xy 0.22733 0.30353) (xy 0.2286 0.2921) (xy 0.22733 0.28067) (xy 0.22733 0.27051) (xy 0.22606 0.25908)
						(xy 0.22352 0.24892) (xy 0.22225 0.23876) (xy 0.21844 0.22733) (xy 0.2159 0.21717) (xy 0.21209 0.20701)
						(xy 0.20701 0.19685) (xy 0.2032 0.18796) (xy 0.19812 0.1778) (xy 0.17272 0.14224) (xy 0.1651 0.13462)
						(xy 0.1651 -0.7366) (xy 0.16256 -0.76835) (xy 0.1524 -0.8001) (xy 0.13716 -0.82804) (xy 0.11684 -0.85344)
						(xy 0.09144 -0.87376) (xy 0.0635 -0.889) (xy 0.03175 -0.89916)
					)
					(width 0)
					(fill yes)
				)
			)
		)
		(pad "47" smd custom
			(at -17.850104 -4.100068 180)
			(size 0.1143 0.1143)
			(layers "B.Cu" "B.Mask" "B.Paste")
			(net "GND")
			(options
				(clearance outline)
				(anchor circle)
			)
			(primitives
				(gr_poly
					(pts
						(xy 0 -0.9017) (xy -0.03175 -0.89916) (xy -0.0635 -0.889) (xy -0.09144 -0.87376) (xy -0.11684 -0.85344)
						(xy -0.13716 -0.82804) (xy -0.1524 -0.8001) (xy -0.16256 -0.76835) (xy -0.1651 -0.7366) (xy -0.1651 -0.19685)
						(xy -0.17272 -0.18923) (xy -0.17907 -0.18034) (xy -0.18669 -0.17145) (xy -0.19177 -0.16256) (xy -0.19812 -0.15367)
						(xy -0.20828 -0.13335) (xy -0.21971 -0.10287) (xy -0.22225 -0.09271) (xy -0.22479 -0.08128) (xy -0.22606 -0.07112)
						(xy -0.2286 -0.05969) (xy -0.2286 -0.01651) (xy -0.22606 -0.00508) (xy -0.22479 0.00508) (xy -0.22225 0.01651)
						(xy -0.21971 0.02667) (xy -0.20828 0.05715) (xy -0.19812 0.07747) (xy -0.19177 0.08636) (xy -0.18669 0.09525)
						(xy -0.17907 0.10414) (xy -0.17272 0.11303) (xy -0.1651 0.12065) (xy -0.1651 0.7366) (xy -0.16256 0.76835)
						(xy -0.1524 0.8001) (xy -0.13716 0.82804) (xy -0.11684 0.85344) (xy -0.09144 0.87376) (xy -0.0635 0.889)
						(xy -0.03175 0.89916) (xy 0 0.9017) (xy 0.03175 0.89916) (xy 0.0635 0.889) (xy 0.09144 0.87376)
						(xy 0.11684 0.85344) (xy 0.13716 0.82804) (xy 0.1524 0.8001) (xy 0.16256 0.76835) (xy 0.1651 0.7366)
						(xy 0.1651 0.11938) (xy 0.17272 0.11176) (xy 0.19812 0.0762) (xy 0.2032 0.06604) (xy 0.20701 0.05715)
						(xy 0.21209 0.04699) (xy 0.2159 0.03683) (xy 0.21844 0.02667) (xy 0.22225 0.01524) (xy 0.22352 0.00508)
						(xy 0.22606 -0.00508) (xy 0.22733 -0.01651) (xy 0.22733 -0.02667) (xy 0.2286 -0.0381) (xy 0.22733 -0.04953)
						(xy 0.22733 -0.05969) (xy 0.22606 -0.07112) (xy 0.22352 -0.08128) (xy 0.22225 -0.09144) (xy 0.21844 -0.10287)
						(xy 0.2159 -0.11303) (xy 0.21209 -0.12319) (xy 0.20701 -0.13335) (xy 0.2032 -0.14224) (xy 0.19812 -0.1524)
						(xy 0.17272 -0.18796) (xy 0.1651 -0.19558) (xy 0.1651 -0.7366) (xy 0.16256 -0.76835) (xy 0.1524 -0.8001)
						(xy 0.13716 -0.82804) (xy 0.11684 -0.85344) (xy 0.09144 -0.87376) (xy 0.0635 -0.889) (xy 0.03175 -0.89916)
					)
					(width 0)
					(fill yes)
				)
			)
		)
		(pad "48" smd custom
			(at -17.549876 4.100068 180)
			(size 0.1143 0.1143)
			(layers "B.Cu" "B.Mask" "B.Paste")
			(net "M_B_DQ22")
			(options
				(clearance outline)
				(anchor circle)
			)
			(primitives
				(gr_poly
					(pts
						(xy 0 -0.9017) (xy -0.03175 -0.89916) (xy -0.0635 -0.889) (xy -0.09144 -0.87376) (xy -0.11684 -0.85344)
						(xy -0.13716 -0.82804) (xy -0.1524 -0.8001) (xy -0.16256 -0.76835) (xy -0.1651 -0.7366) (xy -0.1651 -0.11938)
						(xy -0.17272 -0.11176) (xy -0.19812 -0.0762) (xy -0.2032 -0.06604) (xy -0.20701 -0.05715) (xy -0.21209 -0.04699)
						(xy -0.2159 -0.03683) (xy -0.21844 -0.02667) (xy -0.22225 -0.01524) (xy -0.22352 -0.00508) (xy -0.22606 0.00508)
						(xy -0.22733 0.01651) (xy -0.22733 0.02667) (xy -0.2286 0.0381) (xy -0.22733 0.04953) (xy -0.22733 0.05969)
						(xy -0.22606 0.07112) (xy -0.22352 0.08128) (xy -0.22225 0.09144) (xy -0.21844 0.10287) (xy -0.2159 0.11303)
						(xy -0.21209 0.12319) (xy -0.20701 0.13335) (xy -0.2032 0.14224) (xy -0.19812 0.1524) (xy -0.17272 0.18796)
						(xy -0.1651 0.19558) (xy -0.1651 0.7366) (xy -0.16256 0.76835) (xy -0.1524 0.8001) (xy -0.13716 0.82804)
						(xy -0.11684 0.85344) (xy -0.09144 0.87376) (xy -0.0635 0.889) (xy -0.03175 0.89916) (xy 0 0.9017)
						(xy 0.03175 0.89916) (xy 0.0635 0.889) (xy 0.09144 0.87376) (xy 0.11684 0.85344) (xy 0.13716 0.82804)
						(xy 0.1524 0.8001) (xy 0.16256 0.76835) (xy 0.1651 0.7366) (xy 0.1651 0.19685) (xy 0.17272 0.18923)
						(xy 0.17907 0.18034) (xy 0.18669 0.17145) (xy 0.19177 0.16256) (xy 0.19812 0.15367) (xy 0.20828 0.13335)
						(xy 0.21971 0.10287) (xy 0.22225 0.09271) (xy 0.22479 0.08128) (xy 0.22606 0.07112) (xy 0.2286 0.05969)
						(xy 0.2286 0.01651) (xy 0.22606 0.00508) (xy 0.22479 -0.00508) (xy 0.22225 -0.01651) (xy 0.21971 -0.02667)
						(xy 0.20828 -0.05715) (xy 0.19812 -0.07747) (xy 0.19177 -0.08636) (xy 0.18669 -0.09525) (xy 0.17907 -0.10414)
						(xy 0.17272 -0.11303) (xy 0.1651 -0.12065) (xy 0.1651 -0.7366) (xy 0.16256 -0.76835) (xy 0.1524 -0.8001)
						(xy 0.13716 -0.82804) (xy 0.11684 -0.85344) (xy 0.09144 -0.87376) (xy 0.0635 -0.889) (xy 0.03175 -0.89916)
					)
					(width 0)
					(fill yes)
				)
			)
		)
	)
)
